(kicad_pcb
	(version 20260206)
	(generator "pcbnew")
	(generator_version "10.0")
	(general
		(thickness 1.6)
		(legacy_teardrops no)
	)
	(paper "A4")
	(title_block
		(title "baseboard — 13948-1b.1110WZS1818.brd")
		(comment 1 "Honey Badger (Wiwynn) / footprints 2334-2344 of 2523")
	)
	(layers
		(0 "F.Cu" signal "TOP")
		(4 "In1.Cu" signal "L2GND")
		(6 "In2.Cu" signal "L3")
		(8 "In3.Cu" signal "L4VCC")
		(10 "In4.Cu" signal "L5VCC")
		(12 "In5.Cu" signal "L6")
		(14 "In6.Cu" signal "L7GND")
		(2 "B.Cu" signal "BOTTOM")
		(9 "F.Adhes" user "F.Adhesive")
		(11 "B.Adhes" user "B.Adhesive")
		(13 "F.Paste" user "Package Geometry/Pastemask Top")
		(15 "B.Paste" user "Package Geometry/Pastemask Bottom")
		(5 "F.SilkS" user "Ref Des/Silkscreen Top")
		(7 "B.SilkS" user "Ref Des/Silkscreen Bottom")
		(1 "F.Mask" user "Board Geometry/Soldermask Top")
		(3 "B.Mask" user "Board Geometry/Soldermask Bottom")
		(17 "Dwgs.User" user "User.Drawings")
		(19 "Cmts.User" user "User.Comments")
		(21 "Eco1.User" user "User.Eco1")
		(23 "Eco2.User" user "User.Eco2")
		(25 "Edge.Cuts" user "Board Geometry/Outline")
		(27 "Margin" user)
		(31 "F.CrtYd" user "Package Geometry/Place Bound Top")
		(29 "B.CrtYd" user "Package Geometry/Place Bound Bottom")
		(35 "F.Fab" user "Ref Des/Assembly Top")
		(33 "B.Fab" user "Ref Des/Assembly Bottom")
	)
	(footprint ""
		(layer "B.Cu")
		(at 87.76716 -51.308)
		(property "Reference" "STP12"
			(at 0 0 0)
			(layer "B.SilkS")
			(hide yes)
			(effects
				(font
					(size 1.27 1.27)
				)
				(justify mirror)
			)
		)
		(property "Value" "TPAD28"
			(at -0.0127 -1.8034 0)
			(unlocked yes)
			(layer "B.Fab")
			(hide yes)
			(effects
				(font
					(size 1.016 1.016)
					(thickness 0.1524)
				)
				(justify mirror)
			)
		)
		(property "Device Type" "TPAD28"
			(at -0.0127 -3.3274 0)
			(unlocked yes)
			(layer "B.Fab")
			(hide yes)
			(effects
				(font
					(size 1.016 1.016)
					(thickness 0.1524)
				)
				(justify mirror)
			)
		)
		(duplicate_pad_numbers_are_jumpers no)
		(fp_poly
			(pts
				(arc
					(start 0.3556 0)
					(mid -0.3556 0)
					(end 0.3556 0)
				)
			)
			(stroke
				(width 0)
				(type default)
			)
			(fill no)
			(layer "B.CrtYd")
		)
		(fp_poly
			(pts
				(arc
					(start 0.6096 0)
					(mid -0.6096 0)
					(end 0.6096 0)
				)
			)
			(stroke
				(width 0)
				(type default)
			)
			(fill no)
			(layer "B.Fab")
		)
		(pad "1" smd circle
			(at 0 0 180)
			(size 0.7112 0.7112)
			(layers "B.Cu" "B.Mask" "B.Paste")
			(net "SIO_CLK_1")
		)
	)
	(footprint ""
		(layer "B.Cu")
		(at 113.626646 -38.07968)
		(property "Reference" "STP10"
			(at 0 0 0)
			(layer "B.SilkS")
			(hide yes)
			(effects
				(font
					(size 1.27 1.27)
				)
				(justify mirror)
			)
		)
		(property "Value" "TPAD28"
			(at -0.0127 -1.8034 0)
			(unlocked yes)
			(layer "B.Fab")
			(hide yes)
			(effects
				(font
					(size 1.016 1.016)
					(thickness 0.1524)
				)
				(justify mirror)
			)
		)
		(property "Device Type" "TPAD28"
			(at -0.0127 -3.3274 0)
			(unlocked yes)
			(layer "B.Fab")
			(hide yes)
			(effects
				(font
					(size 1.016 1.016)
					(thickness 0.1524)
				)
				(justify mirror)
			)
		)
		(duplicate_pad_numbers_are_jumpers no)
		(fp_poly
			(pts
				(arc
					(start 0.3556 0)
					(mid -0.3556 0)
					(end 0.3556 0)
				)
			)
			(stroke
				(width 0)
				(type default)
			)
			(fill no)
			(layer "B.CrtYd")
		)
		(fp_poly
			(pts
				(arc
					(start 0.6096 0)
					(mid -0.6096 0)
					(end 0.6096 0)
				)
			)
			(stroke
				(width 0)
				(type default)
			)
			(fill no)
			(layer "B.Fab")
		)
		(pad "1" smd circle
			(at 0 0 180)
			(size 0.7112 0.7112)
			(layers "B.Cu" "B.Mask" "B.Paste")
			(net "IOC_GPIO_29")
		)
	)
	(footprint ""
		(layer "B.Cu")
		(at 109.99216 -30.226)
		(property "Reference" "STP51"
			(at 0 0 0)
			(layer "B.SilkS")
			(hide yes)
			(effects
				(font
					(size 1.27 1.27)
				)
				(justify mirror)
			)
		)
		(property "Value" "TPAD28"
			(at -0.0127 -1.8034 0)
			(unlocked yes)
			(layer "B.Fab")
			(hide yes)
			(effects
				(font
					(size 1.016 1.016)
					(thickness 0.1524)
				)
				(justify mirror)
			)
		)
		(property "Device Type" "TPAD28"
			(at -0.0127 -3.3274 0)
			(unlocked yes)
			(layer "B.Fab")
			(hide yes)
			(effects
				(font
					(size 1.016 1.016)
					(thickness 0.1524)
				)
				(justify mirror)
			)
		)
		(duplicate_pad_numbers_are_jumpers no)
		(fp_poly
			(pts
				(arc
					(start 0.3556 0)
					(mid -0.3556 0)
					(end 0.3556 0)
				)
			)
			(stroke
				(width 0)
				(type default)
			)
			(fill no)
			(layer "B.CrtYd")
		)
		(fp_poly
			(pts
				(arc
					(start 0.6096 0)
					(mid -0.6096 0)
					(end 0.6096 0)
				)
			)
			(stroke
				(width 0)
				(type default)
			)
			(fill no)
			(layer "B.Fab")
		)
		(pad "1" smd circle
			(at 0 0 180)
			(size 0.7112 0.7112)
			(layers "B.Cu" "B.Mask" "B.Paste")
			(net "SPARE1")
		)
	)
	(footprint ""
		(layer "B.Cu")
		(at 299.77334 -182.4101)
		(property "Reference" "TP111"
			(at 0 0 0)
			(layer "B.SilkS")
			(hide yes)
			(effects
				(font
					(size 1.27 1.27)
				)
				(justify mirror)
			)
		)
		(property "Value" "TPAD28"
			(at -0.0127 -1.8034 0)
			(unlocked yes)
			(layer "B.Fab")
			(hide yes)
			(effects
				(font
					(size 1.016 1.016)
					(thickness 0.1524)
				)
				(justify mirror)
			)
		)
		(property "Device Type" "TPAD28"
			(at -0.0127 -3.3274 0)
			(unlocked yes)
			(layer "B.Fab")
			(hide yes)
			(effects
				(font
					(size 1.016 1.016)
					(thickness 0.1524)
				)
				(justify mirror)
			)
		)
		(duplicate_pad_numbers_are_jumpers no)
		(fp_poly
			(pts
				(arc
					(start 0.3556 0)
					(mid -0.3556 0)
					(end 0.3556 0)
				)
			)
			(stroke
				(width 0)
				(type default)
			)
			(fill no)
			(layer "B.CrtYd")
		)
		(fp_poly
			(pts
				(arc
					(start 0.6096 0)
					(mid -0.6096 0)
					(end 0.6096 0)
				)
			)
			(stroke
				(width 0)
				(type default)
			)
			(fill no)
			(layer "B.Fab")
		)
		(pad "1" smd circle
			(at 0 0 180)
			(size 0.7112 0.7112)
			(layers "B.Cu" "B.Mask" "B.Paste")
			(net "TP_BMC_GPIOM3")
		)
	)
	(footprint ""
		(layer "B.Cu")
		(at 115.894612 -205.867)
		(property "Reference" "SR890"
			(at 0 0 0)
			(layer "B.SilkS")
			(hide yes)
			(effects
				(font
					(size 1.27 1.27)
				)
				(justify mirror)
			)
		)
		(property "Value" "0R2J-2-GP"
			(at -0.064008 -3.993896 0)
			(unlocked yes)
			(layer "B.Fab")
			(hide yes)
			(effects
				(font
					(size 1.016 1.016)
					(thickness 0.1524)
				)
				(justify mirror)
			)
		)
		(property "Device Type" "R402H16"
			(at -0.064008 -5.517896 0)
			(unlocked yes)
			(layer "B.Fab")
			(hide yes)
			(effects
				(font
					(size 1.016 1.016)
					(thickness 0.1524)
				)
				(justify mirror)
			)
		)
		(duplicate_pad_numbers_are_jumpers no)
		(fp_line
			(start -0.508 -0.9398)
			(end 0.508 -0.9398)
			(stroke
				(width 0.1524)
				(type default)
			)
			(layer "B.SilkS")
		)
		(fp_line
			(start 0.508 -0.9398)
			(end 0.508 0.9398)
			(stroke
				(width 0.1524)
				(type default)
			)
			(layer "B.SilkS")
		)
		(fp_rect
			(start 0.508 0.9398)
			(end -0.508 -0.9398)
			(stroke
				(width 0)
				(type default)
			)
			(fill no)
			(layer "B.CrtYd")
		)
		(fp_rect
			(start 0.508 0.9398)
			(end -0.508 -0.9398)
			(stroke
				(width 0)
				(type default)
			)
			(fill no)
			(layer "B.Fab")
		)
		(pad "1" smd custom
			(at 0 -0.4445 180)
			(size 0.1397 0.1397)
			(layers "B.Cu" "B.Mask" "B.Paste")
			(net "SAS_HDD_REDV_SER_RX7_N")
			(options
				(clearance outline)
				(anchor circle)
			)
			(primitives
				(gr_poly
					(pts
						(arc
							(start -0.1778 0.2794)
							(mid -0.249642 0.249642)
							(end -0.2794 0.1778)
						)
						(arc
							(start -0.2794 -0.1778)
							(mid -0.249642 -0.249642)
							(end -0.1778 -0.2794)
						)
						(arc
							(start 0.1778 -0.2794)
							(mid 0.249642 -0.249642)
							(end 0.2794 -0.1778)
						)
						(arc
							(start 0.2794 0.1778)
							(mid 0.249642 0.249642)
							(end 0.1778 0.2794)
						)
					)
					(width 0)
					(fill yes)
				)
			)
		)
		(pad "2" smd custom
			(at 0 0.4445 180)
			(size 0.1397 0.1397)
			(layers "B.Cu" "B.Mask" "B.Paste")
			(net "SAS_HDD_CONN_RX7_N")
			(options
				(clearance outline)
				(anchor circle)
			)
			(primitives
				(gr_poly
					(pts
						(arc
							(start -0.1778 0.2794)
							(mid -0.249642 0.249642)
							(end -0.2794 0.1778)
						)
						(arc
							(start -0.2794 -0.1778)
							(mid -0.249642 -0.249642)
							(end -0.1778 -0.2794)
						)
						(arc
							(start 0.1778 -0.2794)
							(mid 0.249642 -0.249642)
							(end 0.2794 -0.1778)
						)
						(arc
							(start 0.2794 0.1778)
							(mid 0.249642 0.249642)
							(end 0.1778 0.2794)
						)
					)
					(width 0)
					(fill yes)
				)
			)
		)
	)
	(footprint ""
		(layer "B.Cu")
		(at 100.083366 -50.2666 180)
		(property "Reference" "SC1031"
			(at 0 0 0)
			(layer "B.SilkS")
			(hide yes)
			(effects
				(font
					(size 1.27 1.27)
				)
				(justify mirror)
			)
		)
		(property "Value" "SC1KP50V2KX-1GP"
			(at -1.1811 -2.7051 180)
			(unlocked yes)
			(layer "B.Fab")
			(hide yes)
			(effects
				(font
					(size 1.016 1.016)
					(thickness 0.1524)
				)
				(justify mirror)
			)
		)
		(property "Device Type" "C402H22"
			(at -1.1811 -4.2291 180)
			(unlocked yes)
			(layer "B.Fab")
			(hide yes)
			(effects
				(font
					(size 1.016 1.016)
					(thickness 0.1524)
				)
				(justify mirror)
			)
		)
		(duplicate_pad_numbers_are_jumpers no)
		(fp_rect
			(start 0.4318 0.9525)
			(end -0.4318 -0.9525)
			(stroke
				(width 0)
				(type default)
			)
			(fill no)
			(layer "B.CrtYd")
		)
		(fp_rect
			(start 0.4318 0.9525)
			(end -0.4318 -0.9525)
			(stroke
				(width 0)
				(type default)
			)
			(fill no)
			(layer "B.Fab")
		)
		(pad "1" smd custom
			(at 0 -0.4445)
			(size 0.1524 0.1524)
			(layers "B.Cu" "B.Mask" "B.Paste")
			(net "P0V955_C")
			(options
				(clearance outline)
				(anchor circle)
			)
			(primitives
				(gr_poly
					(pts
						(arc
							(start 0.3048 0.2032)
							(mid 0.275042 0.275042)
							(end 0.2032 0.3048)
						)
						(arc
							(start -0.2032 0.3048)
							(mid -0.275042 0.275042)
							(end -0.3048 0.2032)
						)
						(arc
							(start -0.3048 -0.2032)
							(mid -0.275042 -0.275042)
							(end -0.2032 -0.3048)
						)
						(arc
							(start 0.2032 -0.3048)
							(mid 0.275042 -0.275042)
							(end 0.3048 -0.2032)
						)
					)
					(width 0)
					(fill yes)
				)
			)
		)
		(pad "2" smd custom
			(at 0 0.4445)
			(size 0.1524 0.1524)
			(layers "B.Cu" "B.Mask" "B.Paste")
			(net "GND")
			(options
				(clearance outline)
				(anchor circle)
			)
			(primitives
				(gr_poly
					(pts
						(arc
							(start 0.3048 0.2032)
							(mid 0.275042 0.275042)
							(end 0.2032 0.3048)
						)
						(arc
							(start -0.2032 0.3048)
							(mid -0.275042 0.275042)
							(end -0.3048 0.2032)
						)
						(arc
							(start -0.3048 -0.2032)
							(mid -0.275042 -0.275042)
							(end -0.2032 -0.3048)
						)
						(arc
							(start 0.2032 -0.3048)
							(mid 0.275042 -0.275042)
							(end 0.3048 -0.2032)
						)
					)
					(width 0)
					(fill yes)
				)
			)
		)
	)
	(footprint ""
		(layer "B.Cu")
		(at 120.38457 -92.6846 90)
		(property "Reference" "SC1143"
			(at 0 0 90)
			(layer "B.SilkS")
			(hide yes)
			(effects
				(font
					(size 1.27 1.27)
				)
				(justify mirror)
			)
		)
		(property "Value" "SCD1U6D3V1KX-GP"
			(at 2.8321 -1.7399 90)
			(unlocked yes)
			(layer "B.Fab")
			(hide yes)
			(effects
				(font
					(size 1.016 1.016)
					(thickness 0.1524)
				)
				(justify mirror)
			)
		)
		(property "Device Type" "C0201H13"
			(at 2.8321 -3.2639 90)
			(unlocked yes)
			(layer "B.Fab")
			(hide yes)
			(effects
				(font
					(size 1.016 1.016)
					(thickness 0.1524)
				)
				(justify mirror)
			)
		)
		(duplicate_pad_numbers_are_jumpers no)
		(fp_rect
			(start 0.2794 0.6477)
			(end -0.2794 -0.6477)
			(stroke
				(width 0)
				(type default)
			)
			(fill no)
			(layer "B.CrtYd")
		)
		(fp_rect
			(start 0.2794 0.6477)
			(end -0.2794 -0.6477)
			(stroke
				(width 0)
				(type default)
			)
			(fill no)
			(layer "B.Fab")
		)
		(pad "1" smd custom
			(at 0 -0.2794 270)
			(size 0.0762 0.0762)
			(layers "B.Cu" "B.Mask" "B.Paste")
			(net "GB_VDDH2")
			(options
				(clearance outline)
				(anchor circle)
			)
			(primitives
				(gr_poly
					(pts
						(arc
							(start 0.1524 0.127)
							(mid 0.137521 0.162921)
							(end 0.1016 0.1778)
						)
						(arc
							(start -0.1016 0.1778)
							(mid -0.137521 0.162921)
							(end -0.1524 0.127)
						)
						(arc
							(start -0.1524 -0.127)
							(mid -0.137521 -0.162921)
							(end -0.1016 -0.1778)
						)
						(arc
							(start 0.1016 -0.1778)
							(mid 0.137521 -0.162921)
							(end 0.1524 -0.127)
						)
					)
					(width 0)
					(fill yes)
				)
			)
		)
		(pad "2" smd custom
			(at 0 0.2794 270)
			(size 0.0762 0.0762)
			(layers "B.Cu" "B.Mask" "B.Paste")
			(net "GND")
			(options
				(clearance outline)
				(anchor circle)
			)
			(primitives
				(gr_poly
					(pts
						(arc
							(start 0.1524 0.127)
							(mid 0.137521 0.162921)
							(end 0.1016 0.1778)
						)
						(arc
							(start -0.1016 0.1778)
							(mid -0.137521 0.162921)
							(end -0.1524 0.127)
						)
						(arc
							(start -0.1524 -0.127)
							(mid -0.137521 -0.162921)
							(end -0.1016 -0.1778)
						)
						(arc
							(start 0.1016 -0.1778)
							(mid 0.137521 -0.162921)
							(end 0.1524 -0.127)
						)
					)
					(width 0)
					(fill yes)
				)
			)
		)
	)
	(footprint ""
		(layer "B.Cu")
		(at 107.696 -95.758 -90)
		(property "Reference" "STP83"
			(at 0 0 90)
			(layer "B.SilkS")
			(hide yes)
			(effects
				(font
					(size 1.27 1.27)
				)
				(justify mirror)
			)
		)
		(property "Value" "TPAD28"
			(at -0.0127 -1.8034 270)
			(unlocked yes)
			(layer "B.Fab")
			(hide yes)
			(effects
				(font
					(size 1.016 1.016)
					(thickness 0.1524)
				)
				(justify mirror)
			)
		)
		(property "Device Type" "TPAD28"
			(at -0.0127 -3.3274 270)
			(unlocked yes)
			(layer "B.Fab")
			(hide yes)
			(effects
				(font
					(size 1.016 1.016)
					(thickness 0.1524)
				)
				(justify mirror)
			)
		)
		(duplicate_pad_numbers_are_jumpers no)
		(fp_poly
			(pts
				(arc
					(start 0 -0.3556)
					(mid 0 0.3556)
					(end 0 -0.3556)
				)
			)
			(stroke
				(width 0)
				(type default)
			)
			(fill no)
			(layer "B.CrtYd")
		)
		(fp_poly
			(pts
				(arc
					(start 0 -0.6096)
					(mid 0 0.6096)
					(end 0 -0.6096)
				)
			)
			(stroke
				(width 0)
				(type default)
			)
			(fill no)
			(layer "B.Fab")
		)
		(pad "1" smd circle
			(at 0 0 90)
			(size 0.7112 0.7112)
			(layers "B.Cu" "B.Mask" "B.Paste")
			(net "EXP_TACH_IN3")
		)
	)
	(footprint ""
		(layer "B.Cu")
		(at 107.169966 -46.609 90)
		(property "Reference" "SC1036"
			(at 0 0 90)
			(layer "B.SilkS")
			(hide yes)
			(effects
				(font
					(size 1.27 1.27)
				)
				(justify mirror)
			)
		)
		(property "Value" "SC1KP50V2KX-1GP"
			(at -1.1811 -2.7051 90)
			(unlocked yes)
			(layer "B.Fab")
			(hide yes)
			(effects
				(font
					(size 1.016 1.016)
					(thickness 0.1524)
				)
				(justify mirror)
			)
		)
		(property "Device Type" "C402H22"
			(at -1.1811 -4.2291 90)
			(unlocked yes)
			(layer "B.Fab")
			(hide yes)
			(effects
				(font
					(size 1.016 1.016)
					(thickness 0.1524)
				)
				(justify mirror)
			)
		)
		(duplicate_pad_numbers_are_jumpers no)
		(fp_rect
			(start 0.4318 0.9525)
			(end -0.4318 -0.9525)
			(stroke
				(width 0)
				(type default)
			)
			(fill no)
			(layer "B.CrtYd")
		)
		(fp_rect
			(start 0.4318 0.9525)
			(end -0.4318 -0.9525)
			(stroke
				(width 0)
				(type default)
			)
			(fill no)
			(layer "B.Fab")
		)
		(pad "1" smd custom
			(at 0 -0.4445 270)
			(size 0.1524 0.1524)
			(layers "B.Cu" "B.Mask" "B.Paste")
			(net "P0V955_C")
			(options
				(clearance outline)
				(anchor circle)
			)
			(primitives
				(gr_poly
					(pts
						(arc
							(start 0.3048 0.2032)
							(mid 0.275042 0.275042)
							(end 0.2032 0.3048)
						)
						(arc
							(start -0.2032 0.3048)
							(mid -0.275042 0.275042)
							(end -0.3048 0.2032)
						)
						(arc
							(start -0.3048 -0.2032)
							(mid -0.275042 -0.275042)
							(end -0.2032 -0.3048)
						)
						(arc
							(start 0.2032 -0.3048)
							(mid 0.275042 -0.275042)
							(end 0.3048 -0.2032)
						)
					)
					(width 0)
					(fill yes)
				)
			)
		)
		(pad "2" smd custom
			(at 0 0.4445 270)
			(size 0.1524 0.1524)
			(layers "B.Cu" "B.Mask" "B.Paste")
			(net "GND")
			(options
				(clearance outline)
				(anchor circle)
			)
			(primitives
				(gr_poly
					(pts
						(arc
							(start 0.3048 0.2032)
							(mid 0.275042 0.275042)
							(end 0.2032 0.3048)
						)
						(arc
							(start -0.2032 0.3048)
							(mid -0.275042 0.275042)
							(end -0.3048 0.2032)
						)
						(arc
							(start -0.3048 -0.2032)
							(mid -0.275042 -0.275042)
							(end -0.2032 -0.3048)
						)
						(arc
							(start 0.2032 -0.3048)
							(mid 0.275042 -0.275042)
							(end 0.3048 -0.2032)
						)
					)
					(width 0)
					(fill yes)
				)
			)
		)
	)
	(footprint ""
		(layer "B.Cu")
		(at 111.762286 -57.299606)
		(property "Reference" "STP152"
			(at 0 0 0)
			(layer "B.SilkS")
			(hide yes)
			(effects
				(font
					(size 1.27 1.27)
				)
				(justify mirror)
			)
		)
		(property "Value" "TPAD28"
			(at -0.0127 -1.8034 0)
			(unlocked yes)
			(layer "B.Fab")
			(hide yes)
			(effects
				(font
					(size 1.016 1.016)
					(thickness 0.1524)
				)
				(justify mirror)
			)
		)
		(property "Device Type" "TPAD28"
			(at -0.0127 -3.3274 0)
			(unlocked yes)
			(layer "B.Fab")
			(hide yes)
			(effects
				(font
					(size 1.016 1.016)
					(thickness 0.1524)
				)
				(justify mirror)
			)
		)
		(duplicate_pad_numbers_are_jumpers no)
		(fp_poly
			(pts
				(arc
					(start 0.3556 0)
					(mid -0.3556 0)
					(end 0.3556 0)
				)
			)
			(stroke
				(width 0)
				(type default)
			)
			(fill no)
			(layer "B.CrtYd")
		)
		(fp_poly
			(pts
				(arc
					(start 0.6096 0)
					(mid -0.6096 0)
					(end 0.6096 0)
				)
			)
			(stroke
				(width 0)
				(type default)
			)
			(fill no)
			(layer "B.Fab")
		)
		(pad "1" smd circle
			(at 0 0 180)
			(size 0.7112 0.7112)
			(layers "B.Cu" "B.Mask" "B.Paste")
			(net "XM_ALE")
		)
	)
	(footprint ""
		(layer "B.Cu")
		(at 115.27917 -96.52)
		(property "Reference" "SC1247"
			(at 0 0 0)
			(layer "B.SilkS")
			(hide yes)
			(effects
				(font
					(size 1.27 1.27)
				)
				(justify mirror)
			)
		)
		(property "Value" "SCD1U6D3V1KX-GP"
			(at 2.8321 -1.7399 0)
			(unlocked yes)
			(layer "B.Fab")
			(hide yes)
			(effects
				(font
					(size 1.016 1.016)
					(thickness 0.1524)
				)
				(justify mirror)
			)
		)
		(property "Device Type" "C0201H13"
			(at 2.8321 -3.2639 0)
			(unlocked yes)
			(layer "B.Fab")
			(hide yes)
			(effects
				(font
					(size 1.016 1.016)
					(thickness 0.1524)
				)
				(justify mirror)
			)
		)
		(duplicate_pad_numbers_are_jumpers no)
		(fp_rect
			(start 0.2794 0.6477)
			(end -0.2794 -0.6477)
			(stroke
				(width 0)
				(type default)
			)
			(fill no)
			(layer "B.CrtYd")
		)
		(fp_rect
			(start 0.2794 0.6477)
			(end -0.2794 -0.6477)
			(stroke
				(width 0)
				(type default)
			)
			(fill no)
			(layer "B.Fab")
		)
		(pad "1" smd custom
			(at 0 -0.2794 180)
			(size 0.0762 0.0762)
			(layers "B.Cu" "B.Mask" "B.Paste")
			(net "P0V9_E")
			(options
				(clearance outline)
				(anchor circle)
			)
			(primitives
				(gr_poly
					(pts
						(arc
							(start 0.1524 0.127)
							(mid 0.137521 0.162921)
							(end 0.1016 0.1778)
						)
						(arc
							(start -0.1016 0.1778)
							(mid -0.137521 0.162921)
							(end -0.1524 0.127)
						)
						(arc
							(start -0.1524 -0.127)
							(mid -0.137521 -0.162921)
							(end -0.1016 -0.1778)
						)
						(arc
							(start 0.1016 -0.1778)
							(mid 0.137521 -0.162921)
							(end 0.1524 -0.127)
						)
					)
					(width 0)
					(fill yes)
				)
			)
		)
		(pad "2" smd custom
			(at 0 0.2794 180)
			(size 0.0762 0.0762)
			(layers "B.Cu" "B.Mask" "B.Paste")
			(net "GND")
			(options
				(clearance outline)
				(anchor circle)
			)
			(primitives
				(gr_poly
					(pts
						(arc
							(start 0.1524 0.127)
							(mid 0.137521 0.162921)
							(end 0.1016 0.1778)
						)
						(arc
							(start -0.1016 0.1778)
							(mid -0.137521 0.162921)
							(end -0.1524 0.127)
						)
						(arc
							(start -0.1524 -0.127)
							(mid -0.137521 -0.162921)
							(end -0.1016 -0.1778)
						)
						(arc
							(start 0.1016 -0.1778)
							(mid 0.137521 -0.162921)
							(end 0.1524 -0.127)
						)
					)
					(width 0)
					(fill yes)
				)
			)
		)
	)
)
